(kicad_pcb
	(version 20260206)
	(generator "pcbnew")
	(generator_version "10.0")
	(general
		(thickness 1.6)
		(legacy_teardrops no)
	)
	(paper "A4")
	(title_block
		(title "Bryce Canyon_F.DPB_16315-1-OCP.brd")
		(comment 1 "Bryce Canyon / footprints 563-565 of 2223")
	)
	(layers
		(0 "F.Cu" signal "TOP")
		(4 "In1.Cu" signal "L2GND")
		(6 "In2.Cu" signal "L3")
		(8 "In3.Cu" signal "L4GND")
		(10 "In4.Cu" signal "L5")
		(12 "In5.Cu" signal "L6VCC")
		(14 "In6.Cu" signal "L7VCC")
		(16 "In7.Cu" signal "L8")
		(18 "In8.Cu" signal "L9GND")
		(20 "In9.Cu" signal "L10")
		(22 "In10.Cu" signal "L11GND")
		(2 "B.Cu" signal "BOTTOM")
		(9 "F.Adhes" user "F.Adhesive")
		(11 "B.Adhes" user "B.Adhesive")
		(13 "F.Paste" user "Package Geometry/Pastemask Top")
		(15 "B.Paste" user "Package Geometry/Pastemask Bottom")
		(5 "F.SilkS" user "Ref Des/Silkscreen Top")
		(7 "B.SilkS" user "Ref Des/Silkscreen Bottom")
		(1 "F.Mask" user "Board Geometry/Soldermask Top")
		(3 "B.Mask" user "Board Geometry/Soldermask Bottom")
		(17 "Dwgs.User" user "User.Drawings")
		(19 "Cmts.User" user "User.Comments")
		(21 "Eco1.User" user "User.Eco1")
		(23 "Eco2.User" user "User.Eco2")
		(25 "Edge.Cuts" user "Board Geometry/Outline")
		(27 "Margin" user)
		(31 "F.CrtYd" user "Package Geometry/Place Bound Top")
		(29 "B.CrtYd" user "Package Geometry/Place Bound Bottom")
		(35 "F.Fab" user "Ref Des/Assembly Top")
		(33 "B.Fab" user "Ref Des/Assembly Bottom")
	)
	(footprint ""
		(layer "F.Cu")
		(at 28.200096 -57.909968 -90)
		(property "Reference" "HDDSAS24"
			(at 0 0 270)
			(layer "F.SilkS")
			(hide yes)
			(effects
				(font
					(size 1.27 1.27)
				)
			)
		)
		(property "Value" "SKT-SAS15P-14P-45-GP"
			(at -20.7645 -8.9789 270)
			(unlocked yes)
			(layer "F.Fab")
			(hide yes)
			(effects
				(font
					(size 1.016 1.016)
					(thickness 0.1524)
				)
			)
		)
		(property "Device Type" "10120818-001C-TRLF"
			(at -20.7645 -10.5029 270)
			(unlocked yes)
			(layer "F.Fab")
			(hide yes)
			(effects
				(font
					(size 1.016 1.016)
					(thickness 0.1524)
				)
			)
		)
		(duplicate_pad_numbers_are_jumpers no)
		(fp_line
			(start 1.651 4.2926)
			(end 1.651 3.0099)
			(stroke
				(width 0.1524)
				(type default)
			)
			(layer "F.SilkS")
		)
		(fp_line
			(start 8.509 4.2926)
			(end 1.651 4.2926)
			(stroke
				(width 0.1524)
				(type default)
			)
			(layer "F.SilkS")
		)
		(fp_line
			(start -23.4188 3.0099)
			(end -23.4188 -3.2512)
			(stroke
				(width 0.1524)
				(type default)
			)
			(layer "F.SilkS")
		)
		(fp_line
			(start 1.651 3.0099)
			(end -23.4188 3.0099)
			(stroke
				(width 0.1524)
				(type default)
			)
			(layer "F.SilkS")
		)
		(fp_line
			(start 8.509 3.0099)
			(end 8.509 4.2926)
			(stroke
				(width 0.1524)
				(type default)
			)
			(layer "F.SilkS")
		)
		(fp_line
			(start 23.4188 3.0099)
			(end 8.509 3.0099)
			(stroke
				(width 0.1524)
				(type default)
			)
			(layer "F.SilkS")
		)
		(fp_line
			(start -23.4188 -3.2512)
			(end 23.4188 -3.2512)
			(stroke
				(width 0.1524)
				(type default)
			)
			(layer "F.SilkS")
		)
		(fp_line
			(start 23.4188 -3.2512)
			(end 23.4188 3.0099)
			(stroke
				(width 0.1524)
				(type default)
			)
			(layer "F.SilkS")
		)
		(fp_line
			(start 15.5067 -3.3401)
			(end 16.2687 -3.3401)
			(stroke
				(width 0.3302)
				(type default)
			)
			(layer "F.SilkS")
		)
		(fp_poly
			(pts
				(xy 15.868904 -3.230372) (xy 16.503904 -3.865372) (xy 15.233904 -3.865372)
			)
			(stroke
				(width 0)
				(type default)
			)
			(fill yes)
			(layer "F.SilkS")
		)
		(fp_poly
			(pts
				(xy -22.8727 -2.7559) (xy 22.8727 -2.7559) (xy 22.8727 2.7559) (xy 8.255 2.7559) (xy 8.255 3.5179)
				(xy 1.905 3.5179) (xy 1.905 2.7559) (xy -22.8727 2.7559)
			)
			(stroke
				(width 0)
				(type default)
			)
			(fill no)
			(layer "F.CrtYd")
		)
		(fp_poly
			(pts
				(xy 1.397 4.5466) (xy 1.397 3.2639) (xy -23.6728 3.2639) (xy -23.6728 -3.5052) (xy 23.6728 -3.5052)
				(xy 23.6728 -0.00635) (xy 22.8727 -0.00635) (xy 22.8727 -2.7559) (xy -22.8727 -2.7559) (xy -22.8727 2.7559)
				(xy 1.905 2.7559) (xy 1.905 3.5179) (xy 8.255 3.5179) (xy 8.255 2.7559) (xy 22.8727 2.7559) (xy 22.8727 0.00635)
				(xy 23.6728 0.00635) (xy 23.6728 3.2639) (xy 8.763 3.2639) (xy 8.763 4.5466)
			)
			(stroke
				(width 0)
				(type default)
			)
			(fill no)
			(layer "F.CrtYd")
		)
		(fp_poly
			(pts
				(xy 1.397 4.5466) (xy 1.397 3.2639) (xy -23.6728 3.2639) (xy -23.6728 -3.5052) (xy 23.6728 -3.5052)
				(xy 23.6728 3.2639) (xy 8.763 3.2639) (xy 8.763 4.5466)
			)
			(stroke
				(width 0)
				(type default)
			)
			(fill no)
			(layer "F.Fab")
		)
		(pad "" np_thru_hole circle
			(at -18.874994 0 270)
			(size 0.254 0.254)
			(drill 1.3462)
			(layers "*.Cu" "*.Mask")
			(clearance 0.9017)
			(thermal_gap 0.9017)
		)
		(pad "" np_thru_hole circle
			(at 18.874994 0 270)
			(size 0.254 0.254)
			(drill 0.9398)
			(layers "*.Cu" "*.Mask")
			(clearance 0.6985)
			(thermal_gap 0.6985)
		)
		(pad "G1" smd rect
			(at 21.874988 0 270)
			(size 2.5908 2.5908)
			(layers "F.Cu" "F.Mask" "F.Paste")
			(net "GND")
		)
		(pad "G2" smd rect
			(at -21.874988 0 270)
			(size 2.5908 2.5908)
			(layers "F.Cu" "F.Mask" "F.Paste")
			(net "GND")
		)
		(pad "P1" smd rect
			(at 1.905 -1.82499 270)
			(size 0.6096 2.3622)
			(layers "F.Cu" "F.Mask" "F.Paste")
			(net "Net_2091")
		)
		(pad "P2" smd rect
			(at 0.635 -1.82499 270)
			(size 0.6096 2.3622)
			(layers "F.Cu" "F.Mask" "F.Paste")
			(net "Net_2092")
		)
		(pad "P3" smd rect
			(at -0.635 -1.82499 270)
			(size 0.6096 2.3622)
			(layers "F.Cu" "F.Mask" "F.Paste")
			(net "Net_2093")
		)
		(pad "P4" smd rect
			(at -1.905 -1.82499 270)
			(size 0.6096 2.3622)
			(layers "F.Cu" "F.Mask" "F.Paste")
			(net "GND")
		)
		(pad "P5" smd rect
			(at -3.175 -1.82499 270)
			(size 0.6096 2.3622)
			(layers "F.Cu" "F.Mask" "F.Paste")
			(net "HDD_PRSNT_24")
		)
		(pad "P6" smd rect
			(at -4.445 -1.82499 270)
			(size 0.6096 2.3622)
			(layers "F.Cu" "F.Mask" "F.Paste")
			(net "GND")
		)
		(pad "P7" smd rect
			(at -5.715 -1.82499 270)
			(size 0.6096 2.3622)
			(layers "F.Cu" "F.Mask" "F.Paste")
			(net "5V_PRE_24")
		)
		(pad "P8" smd rect
			(at -6.985 -1.82499 270)
			(size 0.6096 2.3622)
			(layers "F.Cu" "F.Mask" "F.Paste")
			(net "P5V_HDD24")
		)
		(pad "P9" smd rect
			(at -8.255 -1.82499 270)
			(size 0.6096 2.3622)
			(layers "F.Cu" "F.Mask" "F.Paste")
			(net "P5V_HDD24")
		)
		(pad "P10" smd rect
			(at -9.525 -1.82499 270)
			(size 0.6096 2.3622)
			(layers "F.Cu" "F.Mask" "F.Paste")
			(net "GND")
		)
		(pad "P11" smd rect
			(at -10.795 -1.82499 270)
			(size 0.6096 2.3622)
			(layers "F.Cu" "F.Mask" "F.Paste")
			(net "ACT_HDD_24")
		)
		(pad "P12" smd rect
			(at -12.065 -1.82499 270)
			(size 0.6096 2.3622)
			(layers "F.Cu" "F.Mask" "F.Paste")
			(net "GND")
		)
		(pad "P13" smd rect
			(at -13.335 -1.82499 270)
			(size 0.6096 2.3622)
			(layers "F.Cu" "F.Mask" "F.Paste")
			(net "12V_PRE_24")
		)
		(pad "P14" smd rect
			(at -14.605 -1.82499 270)
			(size 0.6096 2.3622)
			(layers "F.Cu" "F.Mask" "F.Paste")
			(net "P12V_HDD24")
		)
		(pad "P15" smd rect
			(at -15.875 -1.82499 270)
			(size 0.6096 2.3622)
			(layers "F.Cu" "F.Mask" "F.Paste")
			(net "P12V_HDD24")
		)
		(pad "S1" smd rect
			(at 15.875 -1.82499 270)
			(size 0.6096 2.3622)
			(layers "F.Cu" "F.Mask" "F.Paste")
			(net "GND")
		)
		(pad "S2" smd rect
			(at 14.605 -1.82499 270)
			(size 0.6096 2.3622)
			(layers "F.Cu" "F.Mask" "F.Paste")
			(net "SAS_HDD_RX_P24")
		)
		(pad "S3" smd rect
			(at 13.335 -1.82499 270)
			(size 0.6096 2.3622)
			(layers "F.Cu" "F.Mask" "F.Paste")
			(net "SAS_HDD_RX_N24")
		)
		(pad "S4" smd rect
			(at 12.065 -1.82499 270)
			(size 0.6096 2.3622)
			(layers "F.Cu" "F.Mask" "F.Paste")
			(net "GND")
		)
		(pad "S5" smd rect
			(at 10.795 -1.82499 270)
			(size 0.6096 2.3622)
			(layers "F.Cu" "F.Mask" "F.Paste")
			(net "PHY_DRV_A_TO_SCC_A_24_DN")
		)
		(pad "S6" smd rect
			(at 9.525 -1.82499 270)
			(size 0.6096 2.3622)
			(layers "F.Cu" "F.Mask" "F.Paste")
			(net "PHY_DRV_A_TO_SCC_A_24_DP")
		)
		(pad "S7" smd rect
			(at 8.255 -1.82499 270)
			(size 0.6096 2.3622)
			(layers "F.Cu" "F.Mask" "F.Paste")
			(net "GND")
		)
		(pad "S8" smd rect
			(at 7.480046 2.845054 270)
			(size 0.508 2.3622)
			(layers "F.Cu" "F.Mask" "F.Paste")
			(net "GND")
		)
		(pad "S9" smd rect
			(at 6.679946 2.845054 270)
			(size 0.508 2.3622)
			(layers "F.Cu" "F.Mask" "F.Paste")
			(net "Net_462")
		)
		(pad "S10" smd rect
			(at 5.8801 2.845054 270)
			(size 0.508 2.3622)
			(layers "F.Cu" "F.Mask" "F.Paste")
			(net "Net_354")
		)
		(pad "S11" smd rect
			(at 5.08 2.845054 270)
			(size 0.508 2.3622)
			(layers "F.Cu" "F.Mask" "F.Paste")
			(net "GND")
		)
		(pad "S12" smd rect
			(at 4.2799 2.845054 270)
			(size 0.508 2.3622)
			(layers "F.Cu" "F.Mask" "F.Paste")
			(net "Net_390")
		)
		(pad "S13" smd rect
			(at 3.480054 2.845054 270)
			(size 0.508 2.3622)
			(layers "F.Cu" "F.Mask" "F.Paste")
			(net "Net_426")
		)
		(pad "S14" smd rect
			(at 2.679954 2.845054 270)
			(size 0.508 2.3622)
			(layers "F.Cu" "F.Mask" "F.Paste")
			(net "GND")
		)
		(zone
			(layer "F.Cu")
			(hatch none 0.5)
			(connect_pads
				(clearance 0)
			)
			(min_thickness 0.25)
			(keepout
				(tracks not_allowed)
				(vias allowed)
				(pads allowed)
				(copperpour not_allowed)
				(footprints allowed)
			)
			(placement
				(enabled no)
				(sheetname "")
			)
			(fill
				(thermal_gap 0.5)
				(thermal_bridge_width 0.5)
				(island_removal_mode 0)
			)
			(polygon
				(pts
					(xy 31.857696 -74.648568) (xy 24.783796 -74.648568) (xy 24.783796 -81.582768) (xy 25.888696 -81.582768)
					(xy 25.888696 -77.467968) (xy 30.511496 -77.467968) (xy 30.511496 -81.582768) (xy 31.857696 -81.582768)
				)
			)
		)
		(zone
			(layer "F.Cu")
			(hatch none 0.5)
			(connect_pads
				(clearance 0)
			)
			(min_thickness 0.25)
			(keepout
				(tracks allowed)
				(vias not_allowed)
				(pads allowed)
				(copperpour not_allowed)
				(footprints allowed)
			)
			(placement
				(enabled no)
				(sheetname "")
			)
			(fill
				(thermal_gap 0.5)
				(thermal_bridge_width 0.5)
				(island_removal_mode 0)
			)
			(polygon
				(pts
					(xy 31.857696 -74.648568) (xy 24.783796 -74.648568) (xy 24.783796 -81.582768) (xy 25.888696 -81.582768)
					(xy 25.888696 -77.467968) (xy 30.511496 -77.467968) (xy 30.511496 -81.582768) (xy 31.857696 -81.582768)
				)
			)
		)
		(zone
			(layer "F.Cu")
			(hatch none 0.5)
			(connect_pads
				(clearance 0)
			)
			(min_thickness 0.25)
			(keepout
				(tracks allowed)
				(vias not_allowed)
				(pads allowed)
				(copperpour not_allowed)
				(footprints allowed)
			)
			(placement
				(enabled no)
				(sheetname "")
			)
			(fill
				(thermal_gap 0.5)
				(thermal_bridge_width 0.5)
				(island_removal_mode 0)
			)
			(polygon
				(pts
					(xy 31.857696 -41.171368) (xy 24.783796 -41.171368) (xy 24.783796 -34.237168) (xy 25.888696 -34.237168)
					(xy 25.888696 -38.351968) (xy 30.511496 -38.351968) (xy 30.511496 -34.237168) (xy 31.857696 -34.237168)
				)
			)
		)
		(zone
			(layer "F.Cu")
			(hatch none 0.5)
			(connect_pads
				(clearance 0)
			)
			(min_thickness 0.25)
			(keepout
				(tracks not_allowed)
				(vias allowed)
				(pads allowed)
				(copperpour not_allowed)
				(footprints allowed)
			)
			(placement
				(enabled no)
				(sheetname "")
			)
			(fill
				(thermal_gap 0.5)
				(thermal_bridge_width 0.5)
				(island_removal_mode 0)
			)
			(polygon
				(pts
					(xy 31.857696 -41.171368) (xy 24.783796 -41.171368) (xy 24.783796 -34.237168) (xy 25.888696 -34.237168)
					(xy 25.888696 -38.351968) (xy 30.511496 -38.351968) (xy 30.511496 -34.237168) (xy 31.857696 -34.237168)
				)
			)
		)
		(zone
			(layers "F.Cu" "B.Cu" "In1.Cu" "In2.Cu" "In3.Cu" "In4.Cu" "In5.Cu" "In6.Cu"
				"In7.Cu" "In8.Cu" "In9.Cu" "In10.Cu"
			)
			(hatch none 0.5)
			(connect_pads
				(clearance 0)
			)
			(min_thickness 0.25)
			(keepout
				(tracks not_allowed)
				(vias allowed)
				(pads allowed)
				(copperpour not_allowed)
				(footprints allowed)
			)
			(placement
				(enabled no)
				(sheetname "")
			)
			(fill
				(thermal_gap 0.5)
				(thermal_bridge_width 0.5)
				(island_removal_mode 0)
			)
			(polygon
				(pts
					(arc
						(start 28.974796 -39.034974)
						(mid 27.425396 -39.034974)
						(end 28.974796 -39.034974)
					)
				)
			)
		)
		(zone
			(layers "F.Cu" "B.Cu" "In1.Cu" "In2.Cu" "In3.Cu" "In4.Cu" "In5.Cu" "In6.Cu"
				"In7.Cu" "In8.Cu" "In9.Cu" "In10.Cu"
			)
			(hatch none 0.5)
			(connect_pads
				(clearance 0)
			)
			(min_thickness 0.25)
			(keepout
				(tracks not_allowed)
				(vias allowed)
				(pads allowed)
				(copperpour not_allowed)
				(footprints allowed)
			)
			(placement
				(enabled no)
				(sheetname "")
			)
			(fill
				(thermal_gap 0.5)
				(thermal_bridge_width 0.5)
				(island_removal_mode 0)
			)
			(polygon
				(pts
					(arc
						(start 29.177996 -76.784962)
						(mid 27.222196 -76.784962)
						(end 29.177996 -76.784962)
					)
				)
			)
		)
	)
	(footprint ""
		(layer "F.Cu")
		(at 469.904318 -164.295074 90)
		(property "Reference" "R675"
			(at 0 0 90)
			(layer "F.SilkS")
			(hide yes)
			(effects
				(font
					(size 1.27 1.27)
				)
			)
		)
		(property "Value" "200KR2F-L-GP"
			(at 0.064008 -3.993896 90)
			(unlocked yes)
			(layer "F.Fab")
			(hide yes)
			(effects
				(font
					(size 1.016 1.016)
					(thickness 0.1524)
				)
			)
		)
		(property "Device Type" "R402H16"
			(at 0.064008 -5.517896 90)
			(unlocked yes)
			(layer "F.Fab")
			(hide yes)
			(effects
				(font
					(size 1.016 1.016)
					(thickness 0.1524)
				)
			)
		)
		(duplicate_pad_numbers_are_jumpers no)
		(fp_line
			(start 0.508 -0.9398)
			(end -0.508 -0.9398)
			(stroke
				(width 0.1524)
				(type default)
			)
			(layer "F.SilkS")
		)
		(fp_line
			(start -0.508 -0.9398)
			(end -0.508 0.9398)
			(stroke
				(width 0.1524)
				(type default)
			)
			(layer "F.SilkS")
		)
		(fp_rect
			(start -0.508 0.9398)
			(end 0.508 -0.9398)
			(stroke
				(width 0)
				(type default)
			)
			(fill no)
			(layer "F.CrtYd")
		)
		(fp_rect
			(start -0.508 0.9398)
			(end 0.508 -0.9398)
			(stroke
				(width 0)
				(type default)
			)
			(fill no)
			(layer "F.Fab")
		)
		(pad "1" smd custom
			(at 0 -0.4445 90)
			(size 0.1397 0.1397)
			(layers "F.Cu" "F.Mask" "F.Paste")
			(net "SW_HDD_R23")
			(options
				(clearance outline)
				(anchor circle)
			)
			(primitives
				(gr_poly
					(pts
						(arc
							(start -0.1778 -0.2794)
							(mid -0.249642 -0.249642)
							(end -0.2794 -0.1778)
						)
						(arc
							(start -0.2794 0.1778)
							(mid -0.249642 0.249642)
							(end -0.1778 0.2794)
						)
						(arc
							(start 0.1778 0.2794)
							(mid 0.249642 0.249642)
							(end 0.2794 0.1778)
						)
						(arc
							(start 0.2794 -0.1778)
							(mid 0.249642 -0.249642)
							(end 0.1778 -0.2794)
						)
					)
					(width 0)
					(fill yes)
				)
			)
		)
		(pad "2" smd custom
			(at 0 0.4445 90)
			(size 0.1397 0.1397)
			(layers "F.Cu" "F.Mask" "F.Paste")
			(net "SW_HDD_N23")
			(options
				(clearance outline)
				(anchor circle)
			)
			(primitives
				(gr_poly
					(pts
						(arc
							(start -0.1778 -0.2794)
							(mid -0.249642 -0.249642)
							(end -0.2794 -0.1778)
						)
						(arc
							(start -0.2794 0.1778)
							(mid -0.249642 0.249642)
							(end -0.1778 0.2794)
						)
						(arc
							(start 0.1778 0.2794)
							(mid 0.249642 0.249642)
							(end 0.2794 0.1778)
						)
						(arc
							(start 0.2794 -0.1778)
							(mid 0.249642 -0.249642)
							(end 0.1778 -0.2794)
						)
					)
					(width 0)
					(fill yes)
				)
			)
		)
	)
	(footprint ""
		(layer "F.Cu")
		(at 467.469982 -279.816814)
		(property "Reference" "R397"
			(at 0 0 0)
			(layer "F.SilkS")
			(hide yes)
			(effects
				(font
					(size 1.27 1.27)
				)
			)
		)
		(property "Value" "4K7R2J-2-GP"
			(at 0.064008 -3.993896 0)
			(unlocked yes)
			(layer "F.Fab")
			(hide yes)
			(effects
				(font
					(size 1.016 1.016)
					(thickness 0.1524)
				)
			)
		)
		(property "Device Type" "R402H16"
			(at 0.064008 -5.517896 0)
			(unlocked yes)
			(layer "F.Fab")
			(hide yes)
			(effects
				(font
					(size 1.016 1.016)
					(thickness 0.1524)
				)
			)
		)
		(duplicate_pad_numbers_are_jumpers no)
		(fp_line
			(start -0.508 -0.9398)
			(end -0.508 0.9398)
			(stroke
				(width 0.1524)
				(type default)
			)
			(layer "F.SilkS")
		)
		(fp_line
			(start 0.508 -0.9398)
			(end -0.508 -0.9398)
			(stroke
				(width 0.1524)
				(type default)
			)
			(layer "F.SilkS")
		)
		(fp_rect
			(start -0.508 0.9398)
			(end 0.508 -0.9398)
			(stroke
				(width 0)
				(type default)
			)
			(fill no)
			(layer "F.CrtYd")
		)
		(fp_rect
			(start -0.508 0.9398)
			(end 0.508 -0.9398)
			(stroke
				(width 0)
				(type default)
			)
			(fill no)
			(layer "F.Fab")
		)
		(pad "1" smd custom
			(at 0 -0.4445)
			(size 0.1397 0.1397)
			(layers "F.Cu" "F.Mask" "F.Paste")
			(net "P12V_A")
			(options
				(clearance outline)
				(anchor circle)
			)
			(primitives
				(gr_poly
					(pts
						(arc
							(start -0.1778 -0.2794)
							(mid -0.249642 -0.249642)
							(end -0.2794 -0.1778)
						)
						(arc
							(start -0.2794 0.1778)
							(mid -0.249642 0.249642)
							(end -0.1778 0.2794)
						)
						(arc
							(start 0.1778 0.2794)
							(mid 0.249642 0.249642)
							(end 0.2794 0.1778)
						)
						(arc
							(start 0.2794 -0.1778)
							(mid 0.249642 -0.249642)
							(end 0.1778 -0.2794)
						)
					)
					(width 0)
					(fill yes)
				)
			)
		)
		(pad "2" smd custom
			(at 0 0.4445)
			(size 0.1397 0.1397)
			(layers "F.Cu" "F.Mask" "F.Paste")
			(net "SW_HDD_R11")
			(options
				(clearance outline)
				(anchor circle)
			)
			(primitives
				(gr_poly
					(pts
						(arc
							(start -0.1778 -0.2794)
							(mid -0.249642 -0.249642)
							(end -0.2794 -0.1778)
						)
						(arc
							(start -0.2794 0.1778)
							(mid -0.249642 0.249642)
							(end -0.1778 0.2794)
						)
						(arc
							(start 0.1778 0.2794)
							(mid 0.249642 0.249642)
							(end 0.2794 0.1778)
						)
						(arc
							(start 0.2794 -0.1778)
							(mid 0.249642 -0.249642)
							(end 0.1778 -0.2794)
						)
					)
					(width 0)
					(fill yes)
				)
			)
		)
	)
)
